# T6G (Grand Teton) — schematic netlist excerpt (pin names and nets, part order shuffled) for the footprints in the layout excerpt that follows; sources: Cadence DE-HDL packaged netlist, KiCad conversion of 04192023_DAF0TMB3IC0_F0TG_MB_C_brd_V02_OCP.brd

R6141  Q_RES  1K 1% EMPTY  pkg 0402LF  page 84 : A = FM_BOARD_BMC_SKU_ID4 ; B = GND
R44  Q_RES  1K 1% CHIP  pkg 0402LF  page 238 : A = PD_CPU_FRU_WP ; B = GND

(kicad_pcb
	(version 20260206)
	(generator "pcbnew")
	(generator_version "10.0")
	(general
		(thickness 1.6)
		(legacy_teardrops no)
	)
	(paper "A4")
	(title_block
		(title "04192023_DAF0TMB3IC0_F0TG_MB_C_brd_V02_OCP.brd")
		(comment 1 "Grand Teton / footprints 4829-4830 of 8354")
	)
	(layers
		(0 "F.Cu" signal "TOP")
		(4 "In1.Cu" signal "GND")
		(6 "In2.Cu" signal "IN1")
		(8 "In3.Cu" signal "GND1")
		(10 "In4.Cu" signal "IN2")
		(12 "In5.Cu" signal "GND2")
		(14 "In6.Cu" signal "IN3")
		(16 "In7.Cu" signal "GND3")
		(18 "In8.Cu" signal "VCC")
		(20 "In9.Cu" signal "VCC1")
		(22 "In10.Cu" signal "GND4")
		(24 "In11.Cu" signal "IN4")
		(26 "In12.Cu" signal "GND5")
		(28 "In13.Cu" signal "IN5")
		(30 "In14.Cu" signal "GND6")
		(32 "In15.Cu" signal "IN6")
		(34 "In16.Cu" signal "GND7")
		(2 "B.Cu" signal "BOTTOM")
		(9 "F.Adhes" user "F.Adhesive")
		(11 "B.Adhes" user "B.Adhesive")
		(13 "F.Paste" user "Package Geometry/Pastemask Top")
		(15 "B.Paste" user "Package Geometry/Pastemask Bottom")
		(5 "F.SilkS" user "Ref Des/Silkscreen Top")
		(7 "B.SilkS" user "Ref Des/Silkscreen Bottom")
		(1 "F.Mask" user "Board Geometry/Soldermask Top")
		(3 "B.Mask" user "Board Geometry/Soldermask Bottom")
		(17 "Dwgs.User" user "User.Drawings")
		(19 "Cmts.User" user "User.Comments")
		(21 "Eco1.User" user "User.Eco1")
		(23 "Eco2.User" user "User.Eco2")
		(25 "Edge.Cuts" user "Board Geometry/Outline")
		(27 "Margin" user)
		(31 "F.CrtYd" user "Package Geometry/Place Bound Top")
		(29 "B.CrtYd" user "Package Geometry/Place Bound Bottom")
		(35 "F.Fab" user "Ref Des/Assembly Top")
		(33 "B.Fab" user "Ref Des/Assembly Bottom")
	)
	(footprint ""
		(layer "F.Cu")
		(at 163.705794 -116.267484 180)
		(property "Reference" "R6141"
			(at 0 0 180)
			(layer "F.SilkS")
			(hide yes)
			(effects
				(font
					(size 1.27 1.27)
				)
			)
		)
		(property "Value" ""
			(at 0 0 180)
			(layer "F.Fab")
			(effects
				(font
					(size 1.27 1.27)
				)
			)
		)
		(duplicate_pad_numbers_are_jumpers no)
		(fp_line
			(start 0.7874 0.4064)
			(end -0.7874 0.4064)
			(stroke
				(width 0.1524)
				(type default)
			)
			(layer "F.SilkS")
		)
		(fp_line
			(start 0.7874 -0.4064)
			(end 0.7874 0.4064)
			(stroke
				(width 0.1524)
				(type default)
			)
			(layer "F.SilkS")
		)
		(fp_line
			(start -0.7874 0.4064)
			(end -0.7874 -0.4064)
			(stroke
				(width 0.1524)
				(type default)
			)
			(layer "F.SilkS")
		)
		(fp_line
			(start -0.7874 -0.4064)
			(end 0.7874 -0.4064)
			(stroke
				(width 0.1524)
				(type default)
			)
			(layer "F.SilkS")
		)
		(fp_line
			(start 0.67945 0.3048)
			(end 0.120396 0.3048)
			(stroke
				(width 0.1)
				(type default)
			)
			(layer "F.Fab")
		)
		(fp_line
			(start 0.67945 -0.3048)
			(end 0.67945 0.3048)
			(stroke
				(width 0.1)
				(type default)
			)
			(layer "F.Fab")
		)
		(fp_line
			(start 0.12065 -0.2794)
			(end 0.12065 -0.3048)
			(stroke
				(width 0.1)
				(type default)
			)
			(layer "F.Fab")
		)
		(fp_line
			(start 0.12065 -0.3048)
			(end 0.67945 -0.3048)
			(stroke
				(width 0.1)
				(type default)
			)
			(layer "F.Fab")
		)
		(fp_line
			(start 0.120396 0.3048)
			(end 0.120396 0.2794)
			(stroke
				(width 0.1)
				(type default)
			)
			(layer "F.Fab")
		)
		(fp_line
			(start 0.120396 0.2794)
			(end -0.12065 0.2794)
			(stroke
				(width 0.1)
				(type default)
			)
			(layer "F.Fab")
		)
		(fp_line
			(start -0.12065 0.3048)
			(end -0.67945 0.3048)
			(stroke
				(width 0.1)
				(type default)
			)
			(layer "F.Fab")
		)
		(fp_line
			(start -0.12065 0.2794)
			(end -0.12065 0.3048)
			(stroke
				(width 0.1)
				(type default)
			)
			(layer "F.Fab")
		)
		(fp_line
			(start -0.12065 -0.2794)
			(end 0.12065 -0.2794)
			(stroke
				(width 0.1)
				(type default)
			)
			(layer "F.Fab")
		)
		(fp_line
			(start -0.12065 -0.305054)
			(end -0.12065 -0.2794)
			(stroke
				(width 0.1)
				(type default)
			)
			(layer "F.Fab")
		)
		(fp_line
			(start -0.67945 0.3048)
			(end -0.67945 -0.305054)
			(stroke
				(width 0.1)
				(type default)
			)
			(layer "F.Fab")
		)
		(fp_line
			(start -0.67945 -0.305054)
			(end -0.12065 -0.305054)
			(stroke
				(width 0.1)
				(type default)
			)
			(layer "F.Fab")
		)
		(pad "1" smd circle
			(at -0.40005 0 180)
			(size 0 0)
			(layers "F.Cu" "F.Mask" "F.Paste")
			(net "FM_BOARD_BMC_SKU_ID4")
		)
		(pad "2" smd circle
			(at 0.40005 0 180)
			(size 0 0)
			(layers "F.Cu" "F.Mask" "F.Paste")
			(net "GND")
		)
	)
	(footprint ""
		(layer "F.Cu")
		(at 314.567316 -112.58677)
		(property "Reference" "R44"
			(at 0 0 0)
			(layer "F.SilkS")
			(hide yes)
			(effects
				(font
					(size 1.27 1.27)
				)
			)
		)
		(property "Value" ""
			(at 0 0 0)
			(layer "F.Fab")
			(effects
				(font
					(size 1.27 1.27)
				)
			)
		)
		(duplicate_pad_numbers_are_jumpers no)
		(fp_line
			(start -0.7874 -0.4064)
			(end 0.7874 -0.4064)
			(stroke
				(width 0.1524)
				(type default)
			)
			(layer "F.SilkS")
		)
		(fp_line
			(start -0.7874 0.4064)
			(end -0.7874 -0.4064)
			(stroke
				(width 0.1524)
				(type default)
			)
			(layer "F.SilkS")
		)
		(fp_line
			(start 0.7874 -0.4064)
			(end 0.7874 0.4064)
			(stroke
				(width 0.1524)
				(type default)
			)
			(layer "F.SilkS")
		)
		(fp_line
			(start 0.7874 0.4064)
			(end -0.7874 0.4064)
			(stroke
				(width 0.1524)
				(type default)
			)
			(layer "F.SilkS")
		)
		(fp_line
			(start -0.67945 -0.305054)
			(end -0.12065 -0.305054)
			(stroke
				(width 0.1)
				(type default)
			)
			(layer "F.Fab")
		)
		(fp_line
			(start -0.67945 0.3048)
			(end -0.67945 -0.305054)
			(stroke
				(width 0.1)
				(type default)
			)
			(layer "F.Fab")
		)
		(fp_line
			(start -0.12065 -0.305054)
			(end -0.12065 -0.2794)
			(stroke
				(width 0.1)
				(type default)
			)
			(layer "F.Fab")
		)
		(fp_line
			(start -0.12065 -0.2794)
			(end 0.12065 -0.2794)
			(stroke
				(width 0.1)
				(type default)
			)
			(layer "F.Fab")
		)
		(fp_line
			(start -0.12065 0.2794)
			(end -0.12065 0.3048)
			(stroke
				(width 0.1)
				(type default)
			)
			(layer "F.Fab")
		)
		(fp_line
			(start -0.12065 0.3048)
			(end -0.67945 0.3048)
			(stroke
				(width 0.1)
				(type default)
			)
			(layer "F.Fab")
		)
		(fp_line
			(start 0.120396 0.2794)
			(end -0.12065 0.2794)
			(stroke
				(width 0.1)
				(type default)
			)
			(layer "F.Fab")
		)
		(fp_line
			(start 0.120396 0.3048)
			(end 0.120396 0.2794)
			(stroke
				(width 0.1)
				(type default)
			)
			(layer "F.Fab")
		)
		(fp_line
			(start 0.12065 -0.3048)
			(end 0.67945 -0.3048)
			(stroke
				(width 0.1)
				(type default)
			)
			(layer "F.Fab")
		)
		(fp_line
			(start 0.12065 -0.2794)
			(end 0.12065 -0.3048)
			(stroke
				(width 0.1)
				(type default)
			)
			(layer "F.Fab")
		)
		(fp_line
			(start 0.67945 -0.3048)
			(end 0.67945 0.3048)
			(stroke
				(width 0.1)
				(type default)
			)
			(layer "F.Fab")
		)
		(fp_line
			(start 0.67945 0.3048)
			(end 0.120396 0.3048)
			(stroke
				(width 0.1)
				(type default)
			)
			(layer "F.Fab")
		)
		(pad "1" smd circle
			(at -0.40005 0)
			(size 0 0)
			(layers "F.Cu" "F.Mask" "F.Paste")
			(net "PD_CPU_FRU_WP")
		)
		(pad "2" smd circle
			(at 0.40005 0)
			(size 0 0)
			(layers "F.Cu" "F.Mask" "F.Paste")
			(net "GND")
		)
	)
)
